(kicad_pcb
	(version 20260206)
	(generator "pcbnew")
	(generator_version "10.0")
	(general
		(thickness 1.6)
		(legacy_teardrops no)
	)
	(paper "A4")
	(title_block
		(title "v1-chassis-manager — T6M_CM_d_v01_1031_1645.brd")
		(comment 1 "Open CloudServer (Microsoft) / footprints 596-605 of 2512")
	)
	(layers
		(0 "F.Cu" signal "TOP")
		(4 "In1.Cu" signal "GND1")
		(6 "In2.Cu" signal "IN1")
		(8 "In3.Cu" signal "VCC1")
		(10 "In4.Cu" signal "VCC2")
		(12 "In5.Cu" signal "GND2")
		(14 "In6.Cu" signal "IN2")
		(16 "In7.Cu" signal "IN3")
		(18 "In8.Cu" signal "GND3")
		(2 "B.Cu" signal "BOTTOM")
		(9 "F.Adhes" user "F.Adhesive")
		(11 "B.Adhes" user "B.Adhesive")
		(13 "F.Paste" user "Package Geometry/Pastemask Top")
		(15 "B.Paste" user "Package Geometry/Pastemask Bottom")
		(5 "F.SilkS" user "Ref Des/Silkscreen Top")
		(7 "B.SilkS" user "Ref Des/Silkscreen Bottom")
		(1 "F.Mask" user "Board Geometry/Soldermask Top")
		(3 "B.Mask" user "Board Geometry/Soldermask Bottom")
		(17 "Dwgs.User" user "User.Drawings")
		(19 "Cmts.User" user "User.Comments")
		(21 "Eco1.User" user "User.Eco1")
		(23 "Eco2.User" user "User.Eco2")
		(25 "Edge.Cuts" user "Board Geometry/Outline")
		(27 "Margin" user)
		(31 "F.CrtYd" user "Package Geometry/Place Bound Top")
		(29 "B.CrtYd" user "Package Geometry/Place Bound Bottom")
		(35 "F.Fab" user "Ref Des/Assembly Top")
		(33 "B.Fab" user "Ref Des/Assembly Bottom")
	)
	(footprint ""
		(layer "F.Cu")
		(at 99.182428 -162.227768 90)
		(property "Reference" "R1127"
			(at -73.405492 87.879682 90)
			(unlocked yes)
			(layer "F.SilkS")
			(effects
				(font
					(size 0.7874 0.5842)
					(thickness 0.1524)
				)
				(justify left)
			)
		)
		(property "Value" ""
			(at 0 0 90)
			(layer "F.Fab")
			(effects
				(font
					(size 1.27 1.27)
				)
			)
		)
		(duplicate_pad_numbers_are_jumpers no)
		(fp_line
			(start 0.7874 -0.4064)
			(end 0.7874 0.4064)
			(stroke
				(width 0.1524)
				(type default)
			)
			(layer "F.SilkS")
		)
		(fp_line
			(start -0.7874 -0.4064)
			(end 0.7874 -0.4064)
			(stroke
				(width 0.1524)
				(type default)
			)
			(layer "F.SilkS")
		)
		(fp_line
			(start 0.7874 0.4064)
			(end -0.7874 0.4064)
			(stroke
				(width 0.1524)
				(type default)
			)
			(layer "F.SilkS")
		)
		(fp_line
			(start -0.7874 0.4064)
			(end -0.7874 -0.4064)
			(stroke
				(width 0.1524)
				(type default)
			)
			(layer "F.SilkS")
		)
		(fp_poly
			(pts
				(xy -0.508 0.2794) (xy -0.508 0.2286) (xy -0.635 0.2286) (xy -0.635 -0.254) (xy -0.5334 -0.254)
				(xy -0.5334 -0.2794) (xy 0.5334 -0.2794) (xy 0.5334 -0.254) (xy 0.635 -0.254) (xy 0.635 0.254) (xy 0.5334 0.254)
				(xy 0.5334 0.2794)
			)
			(stroke
				(width 0)
				(type default)
			)
			(fill no)
			(layer "F.CrtYd")
		)
		(pad "1" smd rect
			(at 0.40005 0 90)
			(size 0.4572 0.508)
			(layers "F.Cu" "F.Mask" "F.Paste")
			(net "N52411069")
		)
		(pad "2" smd rect
			(at -0.40005 0 90)
			(size 0.4572 0.508)
			(layers "F.Cu" "F.Mask" "F.Paste")
			(net "N52411040")
		)
	)
	(footprint ""
		(layer "F.Cu")
		(at 123.70816 -172.625512)
		(property "Reference" "C566"
			(at 30.127448 47.916338 0)
			(unlocked yes)
			(layer "F.SilkS")
			(effects
				(font
					(size 0.7874 0.5842)
					(thickness 0.1524)
				)
				(justify left)
			)
		)
		(property "Value" ""
			(at 0 0 0)
			(layer "F.Fab")
			(effects
				(font
					(size 1.27 1.27)
				)
			)
		)
		(duplicate_pad_numbers_are_jumpers no)
		(fp_line
			(start -0.7874 -0.4064)
			(end 0.7874 -0.4064)
			(stroke
				(width 0.1524)
				(type default)
			)
			(layer "F.SilkS")
		)
		(fp_line
			(start -0.7874 0.4064)
			(end -0.7874 -0.4064)
			(stroke
				(width 0.1524)
				(type default)
			)
			(layer "F.SilkS")
		)
		(fp_line
			(start 0 0.381)
			(end 0 -0.381)
			(stroke
				(width 0.1524)
				(type default)
			)
			(layer "F.SilkS")
		)
		(fp_line
			(start 0.7874 -0.4064)
			(end 0.7874 0.4064)
			(stroke
				(width 0.1524)
				(type default)
			)
			(layer "F.SilkS")
		)
		(fp_line
			(start 0.7874 0.4064)
			(end -0.7874 0.4064)
			(stroke
				(width 0.1524)
				(type default)
			)
			(layer "F.SilkS")
		)
		(fp_poly
			(pts
				(xy -0.5334 0.254) (xy -0.635 0.254) (xy -0.635 0.2286) (xy -0.635 -0.254) (xy -0.5334 -0.254) (xy -0.5334 -0.2794)
				(xy 0.5334 -0.2794) (xy 0.5334 -0.254) (xy 0.635 -0.254) (xy 0.635 0.254) (xy 0.5334 0.254) (xy 0.5334 0.2794)
				(xy -0.508 0.2794) (xy -0.5334 0.2794)
			)
			(stroke
				(width 0)
				(type default)
			)
			(fill no)
			(layer "F.CrtYd")
		)
		(pad "1" smd rect
			(at 0.40005 0)
			(size 0.4572 0.508)
			(layers "F.Cu" "F.Mask" "F.Paste")
			(net "GND")
		)
		(pad "2" smd rect
			(at -0.40005 0)
			(size 0.4572 0.508)
			(layers "F.Cu" "F.Mask" "F.Paste")
			(net "P3V3_NODE1")
		)
	)
	(footprint ""
		(layer "F.Cu")
		(at 79.984346 -77.187552)
		(property "Reference" "R74"
			(at -0.33655 16.248888 0)
			(unlocked yes)
			(layer "F.SilkS")
			(effects
				(font
					(size 0.7874 0.5842)
					(thickness 0.1524)
				)
				(justify left)
			)
		)
		(property "Value" ""
			(at 0 0 0)
			(layer "F.Fab")
			(effects
				(font
					(size 1.27 1.27)
				)
			)
		)
		(duplicate_pad_numbers_are_jumpers no)
		(fp_line
			(start -0.7874 -0.4064)
			(end 0.7874 -0.4064)
			(stroke
				(width 0.1524)
				(type default)
			)
			(layer "F.SilkS")
		)
		(fp_line
			(start -0.7874 0.4064)
			(end -0.7874 -0.4064)
			(stroke
				(width 0.1524)
				(type default)
			)
			(layer "F.SilkS")
		)
		(fp_line
			(start 0.7874 -0.4064)
			(end 0.7874 0.4064)
			(stroke
				(width 0.1524)
				(type default)
			)
			(layer "F.SilkS")
		)
		(fp_line
			(start 0.7874 0.4064)
			(end -0.7874 0.4064)
			(stroke
				(width 0.1524)
				(type default)
			)
			(layer "F.SilkS")
		)
		(fp_poly
			(pts
				(xy -0.508 0.2794) (xy -0.508 0.2286) (xy -0.635 0.2286) (xy -0.635 -0.254) (xy -0.5334 -0.254)
				(xy -0.5334 -0.2794) (xy 0.5334 -0.2794) (xy 0.5334 -0.254) (xy 0.635 -0.254) (xy 0.635 0.254) (xy 0.5334 0.254)
				(xy 0.5334 0.2794)
			)
			(stroke
				(width 0)
				(type default)
			)
			(fill no)
			(layer "F.CrtYd")
		)
		(pad "1" smd rect
			(at 0.40005 0)
			(size 0.4572 0.508)
			(layers "F.Cu" "F.Mask" "F.Paste")
			(net "P1V05_NODE1")
		)
		(pad "2" smd rect
			(at -0.40005 0)
			(size 0.4572 0.508)
			(layers "F.Cu" "F.Mask" "F.Paste")
			(net "XDP_SOC_CPU_NODE1_TMS")
		)
	)
	(footprint ""
		(layer "F.Cu")
		(at 108.31576 -188.126624 90)
		(property "Reference" "C656"
			(at 5.151882 0.791972 90)
			(unlocked yes)
			(layer "F.SilkS")
			(effects
				(font
					(size 0.7874 0.5842)
					(thickness 0.1524)
				)
				(justify left)
			)
		)
		(property "Value" ""
			(at 0 0 90)
			(layer "F.Fab")
			(effects
				(font
					(size 1.27 1.27)
				)
			)
		)
		(duplicate_pad_numbers_are_jumpers no)
		(fp_line
			(start 0.7874 -0.4064)
			(end 0.7874 0.4064)
			(stroke
				(width 0.1524)
				(type default)
			)
			(layer "F.SilkS")
		)
		(fp_line
			(start -0.7874 -0.4064)
			(end 0.7874 -0.4064)
			(stroke
				(width 0.1524)
				(type default)
			)
			(layer "F.SilkS")
		)
		(fp_line
			(start 0 0.381)
			(end 0 -0.381)
			(stroke
				(width 0.1524)
				(type default)
			)
			(layer "F.SilkS")
		)
		(fp_line
			(start 0.7874 0.4064)
			(end -0.7874 0.4064)
			(stroke
				(width 0.1524)
				(type default)
			)
			(layer "F.SilkS")
		)
		(fp_line
			(start -0.7874 0.4064)
			(end -0.7874 -0.4064)
			(stroke
				(width 0.1524)
				(type default)
			)
			(layer "F.SilkS")
		)
		(fp_poly
			(pts
				(xy -0.5334 0.254) (xy -0.635 0.254) (xy -0.635 0.2286) (xy -0.635 -0.254) (xy -0.5334 -0.254) (xy -0.5334 -0.2794)
				(xy 0.5334 -0.2794) (xy 0.5334 -0.254) (xy 0.635 -0.254) (xy 0.635 0.254) (xy 0.5334 0.254) (xy 0.5334 0.2794)
				(xy -0.508 0.2794) (xy -0.5334 0.2794)
			)
			(stroke
				(width 0)
				(type default)
			)
			(fill no)
			(layer "F.CrtYd")
		)
		(pad "1" smd rect
			(at 0.40005 0 90)
			(size 0.4572 0.508)
			(layers "F.Cu" "F.Mask" "F.Paste")
			(net "T6_NODE4_EN_R")
		)
		(pad "2" smd rect
			(at -0.40005 0 90)
			(size 0.4572 0.508)
			(layers "F.Cu" "F.Mask" "F.Paste")
			(net "GND")
		)
	)
	(footprint ""
		(layer "F.Cu")
		(at 83.84921 -124.536962 -90)
		(property "Reference" "TP174"
			(at 0 0 270)
			(layer "F.SilkS")
			(hide yes)
			(effects
				(font
					(size 1.27 1.27)
				)
			)
		)
		(property "Value" ""
			(at 0 0 270)
			(layer "F.Fab")
			(effects
				(font
					(size 1.27 1.27)
				)
			)
		)
		(duplicate_pad_numbers_are_jumpers no)
		(fp_poly
			(pts
				(arc
					(start 0 -0.3302)
					(mid 0 0.3302)
					(end 0 -0.3302)
				)
			)
			(stroke
				(width 0)
				(type default)
			)
			(fill no)
			(layer "B.CrtYd")
		)
		(pad "1" thru_hole circle
			(at 0 0 270)
			(size 0.508 0.508)
			(drill 0.254)
			(layers "*.Cu" "*.Mask")
			(remove_unused_layers no)
			(net "N53313325")
			(clearance 0.127)
			(thermal_gap 0.127)
			(padstack
				(mode front_inner_back)
				(layer "Inner"
					(shape circle)
					(size 0.508 0.508)
					(clearance 0.127)
				)
				(layer "B.Cu"
					(shape circle)
					(size 0.6604 0.6604)
					(clearance 0.0508)
				)
			)
		)
	)
	(footprint ""
		(layer "F.Cu")
		(at 13.79093 -127.21336 180)
		(property "Reference" "PC59"
			(at 3.473958 -0.133604 0)
			(unlocked yes)
			(layer "F.SilkS")
			(effects
				(font
					(size 0.7874 0.5842)
					(thickness 0.1524)
				)
			)
		)
		(property "Value" ""
			(at 0 0 180)
			(layer "F.Fab")
			(effects
				(font
					(size 1.27 1.27)
				)
			)
		)
		(duplicate_pad_numbers_are_jumpers no)
		(fp_line
			(start 1.2954 0.5842)
			(end -1.2954 0.5842)
			(stroke
				(width 0.1524)
				(type default)
			)
			(layer "F.SilkS")
		)
		(fp_line
			(start 1.2954 -0.5842)
			(end 1.2954 0.5842)
			(stroke
				(width 0.1524)
				(type default)
			)
			(layer "F.SilkS")
		)
		(fp_line
			(start 0 -0.5842)
			(end 0 0.5842)
			(stroke
				(width 0.1524)
				(type default)
			)
			(layer "F.SilkS")
		)
		(fp_line
			(start -1.2954 0.5842)
			(end -1.2954 -0.5842)
			(stroke
				(width 0.1524)
				(type default)
			)
			(layer "F.SilkS")
		)
		(fp_line
			(start -1.2954 -0.5842)
			(end 1.2954 -0.5842)
			(stroke
				(width 0.1524)
				(type default)
			)
			(layer "F.SilkS")
		)
		(fp_poly
			(pts
				(xy 0.8636 -0.4572) (xy 0.8636 -0.3556) (xy 1.143 -0.3556) (xy 1.143 0.3556) (xy 0.8636 0.3556)
				(xy 0.8636 0.4572) (xy -0.8636 0.4572) (xy -0.8636 0.3556) (xy -1.143 0.3556) (xy -1.143 -0.3556)
				(xy -0.8636 -0.3556) (xy -0.8636 -0.4572)
			)
			(stroke
				(width 0)
				(type default)
			)
			(fill no)
			(layer "F.CrtYd")
		)
		(fp_line
			(start 0.884936 0.504952)
			(end -0.884936 0.504952)
			(stroke
				(width 0.1)
				(type default)
			)
			(layer "F.Fab")
		)
		(fp_line
			(start 0.884936 -0.504952)
			(end 0.884936 0.504952)
			(stroke
				(width 0.1)
				(type default)
			)
			(layer "F.Fab")
		)
		(fp_line
			(start -0.884936 0.504952)
			(end -0.884936 -0.504952)
			(stroke
				(width 0.1)
				(type default)
			)
			(layer "F.Fab")
		)
		(fp_line
			(start -0.884936 -0.504952)
			(end 0.884936 -0.504952)
			(stroke
				(width 0.1)
				(type default)
			)
			(layer "F.Fab")
		)
		(pad "1" smd rect
			(at 0.7366 0 270)
			(size 0.7112 0.8128)
			(layers "F.Cu" "F.Mask" "F.Paste")
			(net "GND")
		)
		(pad "2" smd rect
			(at -0.7366 0 270)
			(size 0.7112 0.8128)
			(layers "F.Cu" "F.Mask" "F.Paste")
			(net "P5V_STB_NODE1")
		)
	)
	(footprint ""
		(layer "F.Cu")
		(at 163.990782 -72.313546 90)
		(property "Reference" "PJ3"
			(at 0.243586 3.007868 0)
			(unlocked yes)
			(layer "F.SilkS")
			(effects
				(font
					(size 0.7874 0.5842)
					(thickness 0.1524)
				)
				(justify left)
			)
		)
		(property "Value" ""
			(at 0 0 90)
			(layer "F.Fab")
			(effects
				(font
					(size 1.27 1.27)
				)
			)
		)
		(duplicate_pad_numbers_are_jumpers no)
		(fp_poly
			(pts
				(xy 0.2794 0.907796) (xy 0.254 0.907796) (xy 0.254 1.0414) (xy -0.254 1.0414) (xy -0.254 1.034796)
				(xy -0.254 0.933196) (xy -0.2794 0.933196) (xy -0.2794 -0.133604) (xy -0.254 -0.133604) (xy -0.254 -0.235204)
				(xy 0.254 -0.235204) (xy 0.254 -0.133604) (xy 0.2794 -0.133604)
			)
			(stroke
				(width 0)
				(type default)
			)
			(fill no)
			(layer "F.CrtYd")
		)
		(pad "1" smd custom
			(at 0 -0.000254 90)
			(size 0.127 0.127)
			(layers "F.Cu" "F.Mask" "F.Paste")
			(net "FM_CPLD_NODE1_P1V0_EN")
			(options
				(clearance outline)
				(anchor circle)
			)
			(primitives
				(gr_poly
					(pts
						(xy -0.127 0.508) (xy -0.127 -0.0508) (xy -0.254 -0.0508) (xy -0.254 -0.508) (xy 0.254 -0.508)
						(xy 0.254 -0.0508) (xy 0.127 -0.0508) (xy 0.127 0.508)
					)
					(width 0)
					(fill yes)
				)
			)
		)
		(pad "2" smd rect
			(at 0 0.799846 180)
			(size 0.4572 0.508)
			(layers "F.Cu" "F.Mask" "F.Paste")
			(net "N47241340")
		)
		(zone
			(layer "F.Cu")
			(hatch none 0.5)
			(connect_pads
				(clearance 0)
			)
			(min_thickness 0.25)
			(keepout
				(tracks allowed)
				(vias not_allowed)
				(pads allowed)
				(copperpour not_allowed)
				(footprints allowed)
			)
			(placement
				(enabled no)
				(sheetname "")
			)
			(fill
				(thermal_gap 0.5)
				(thermal_bridge_width 0.5)
				(island_removal_mode 0)
			)
			(polygon
				(pts
					(xy 165.076378 -72.008746) (xy 165.076378 -72.618346) (xy 163.704778 -72.618346) (xy 163.704778 -72.008746)
				)
			)
		)
	)
	(footprint ""
		(layer "F.Cu")
		(at 126.552452 -153.67635 90)
		(property "Reference" "R283"
			(at -111.020352 -58.8264 90)
			(unlocked yes)
			(layer "F.SilkS")
			(effects
				(font
					(size 0.7874 0.5842)
					(thickness 0.1524)
				)
				(justify left)
			)
		)
		(property "Value" ""
			(at 0 0 90)
			(layer "F.Fab")
			(effects
				(font
					(size 1.27 1.27)
				)
			)
		)
		(duplicate_pad_numbers_are_jumpers no)
		(fp_line
			(start 0.7874 -0.4064)
			(end 0.7874 0.4064)
			(stroke
				(width 0.1524)
				(type default)
			)
			(layer "F.SilkS")
		)
		(fp_line
			(start -0.7874 -0.4064)
			(end 0.7874 -0.4064)
			(stroke
				(width 0.1524)
				(type default)
			)
			(layer "F.SilkS")
		)
		(fp_line
			(start 0.7874 0.4064)
			(end -0.7874 0.4064)
			(stroke
				(width 0.1524)
				(type default)
			)
			(layer "F.SilkS")
		)
		(fp_line
			(start -0.7874 0.4064)
			(end -0.7874 -0.4064)
			(stroke
				(width 0.1524)
				(type default)
			)
			(layer "F.SilkS")
		)
		(fp_poly
			(pts
				(xy -0.508 0.2794) (xy -0.508 0.2286) (xy -0.635 0.2286) (xy -0.635 -0.254) (xy -0.5334 -0.254)
				(xy -0.5334 -0.2794) (xy 0.5334 -0.2794) (xy 0.5334 -0.254) (xy 0.635 -0.254) (xy 0.635 0.254) (xy 0.5334 0.254)
				(xy 0.5334 0.2794)
			)
			(stroke
				(width 0)
				(type default)
			)
			(fill no)
			(layer "F.CrtYd")
		)
		(pad "1" smd rect
			(at 0.40005 0 90)
			(size 0.4572 0.508)
			(layers "F.Cu" "F.Mask" "F.Paste")
			(net "P3V3_NODE1")
		)
		(pad "2" smd rect
			(at -0.40005 0 90)
			(size 0.4572 0.508)
			(layers "F.Cu" "F.Mask" "F.Paste")
			(net "PCIE_SW_TEST2")
		)
	)
	(footprint ""
		(layer "F.Cu")
		(at 168.87698 -171.55287 90)
		(property "Reference" "C564"
			(at -0.401828 0.795274 0)
			(unlocked yes)
			(layer "F.SilkS")
			(effects
				(font
					(size 0.7874 0.5842)
					(thickness 0.1524)
				)
				(justify left)
			)
		)
		(property "Value" ""
			(at 0 0 90)
			(layer "F.Fab")
			(effects
				(font
					(size 1.27 1.27)
				)
			)
		)
		(duplicate_pad_numbers_are_jumpers no)
		(fp_line
			(start 0.7874 -0.4064)
			(end 0.7874 0.4064)
			(stroke
				(width 0.1524)
				(type default)
			)
			(layer "F.SilkS")
		)
		(fp_line
			(start -0.7874 -0.4064)
			(end 0.7874 -0.4064)
			(stroke
				(width 0.1524)
				(type default)
			)
			(layer "F.SilkS")
		)
		(fp_line
			(start 0 0.381)
			(end 0 -0.381)
			(stroke
				(width 0.1524)
				(type default)
			)
			(layer "F.SilkS")
		)
		(fp_line
			(start 0.7874 0.4064)
			(end -0.7874 0.4064)
			(stroke
				(width 0.1524)
				(type default)
			)
			(layer "F.SilkS")
		)
		(fp_line
			(start -0.7874 0.4064)
			(end -0.7874 -0.4064)
			(stroke
				(width 0.1524)
				(type default)
			)
			(layer "F.SilkS")
		)
		(fp_poly
			(pts
				(xy -0.5334 0.254) (xy -0.635 0.254) (xy -0.635 0.2286) (xy -0.635 -0.254) (xy -0.5334 -0.254) (xy -0.5334 -0.2794)
				(xy 0.5334 -0.2794) (xy 0.5334 -0.254) (xy 0.635 -0.254) (xy 0.635 0.254) (xy 0.5334 0.254) (xy 0.5334 0.2794)
				(xy -0.508 0.2794) (xy -0.5334 0.2794)
			)
			(stroke
				(width 0)
				(type default)
			)
			(fill no)
			(layer "F.CrtYd")
		)
		(pad "1" smd rect
			(at 0.40005 0 90)
			(size 0.4572 0.508)
			(layers "F.Cu" "F.Mask" "F.Paste")
			(net "GND")
		)
		(pad "2" smd rect
			(at -0.40005 0 90)
			(size 0.4572 0.508)
			(layers "F.Cu" "F.Mask" "F.Paste")
			(net "N54365625")
		)
	)
	(footprint ""
		(layer "F.Cu")
		(at 91.102434 -183.778398 180)
		(property "Reference" "C693"
			(at 1.458214 7.22757 0)
			(unlocked yes)
			(layer "F.SilkS")
			(effects
				(font
					(size 0.7874 0.5842)
					(thickness 0.1524)
				)
				(justify left)
			)
		)
		(property "Value" ""
			(at 0 0 180)
			(layer "F.Fab")
			(effects
				(font
					(size 1.27 1.27)
				)
			)
		)
		(duplicate_pad_numbers_are_jumpers no)
		(fp_line
			(start 0.7874 0.4064)
			(end -0.7874 0.4064)
			(stroke
				(width 0.1524)
				(type default)
			)
			(layer "F.SilkS")
		)
		(fp_line
			(start 0.7874 -0.4064)
			(end 0.7874 0.4064)
			(stroke
				(width 0.1524)
				(type default)
			)
			(layer "F.SilkS")
		)
		(fp_line
			(start 0 0.381)
			(end 0 -0.381)
			(stroke
				(width 0.1524)
				(type default)
			)
			(layer "F.SilkS")
		)
		(fp_line
			(start -0.7874 0.4064)
			(end -0.7874 -0.4064)
			(stroke
				(width 0.1524)
				(type default)
			)
			(layer "F.SilkS")
		)
		(fp_line
			(start -0.7874 -0.4064)
			(end 0.7874 -0.4064)
			(stroke
				(width 0.1524)
				(type default)
			)
			(layer "F.SilkS")
		)
		(fp_poly
			(pts
				(xy -0.5334 0.254) (xy -0.635 0.254) (xy -0.635 0.2286) (xy -0.635 -0.254) (xy -0.5334 -0.254) (xy -0.5334 -0.2794)
				(xy 0.5334 -0.2794) (xy 0.5334 -0.254) (xy 0.635 -0.254) (xy 0.635 0.254) (xy 0.5334 0.254) (xy 0.5334 0.2794)
				(xy -0.508 0.2794) (xy -0.5334 0.2794)
			)
			(stroke
				(width 0)
				(type default)
			)
			(fill no)
			(layer "F.CrtYd")
		)
		(pad "1" smd rect
			(at 0.40005 0 180)
			(size 0.4572 0.508)
			(layers "F.Cu" "F.Mask" "F.Paste")
			(net "UART_T5_NODE4_TXD_R")
		)
		(pad "2" smd rect
			(at -0.40005 0 180)
			(size 0.4572 0.508)
			(layers "F.Cu" "F.Mask" "F.Paste")
			(net "GND")
		)
	)
)
